(kicad_pcb
	(version 20241229)
	(generator "pcbnew")
	(generator_version "9.0")
	(general
		(thickness 1.711)
		(legacy_teardrops no)
	)
	(paper "A4")
	(title_block
		(title "Antmicro Baseboard for Jetson AGX Thor")
		(date "2026-02-18")
		(rev "1.1.0")
		(company "Antmicro Ltd")
		(comment 1 "www.antmicro.com")
		(comment 9 "footprints 833-836 of 1170")
	)
	(layers
		(0 "F.Cu" signal)
		(4 "In1.Cu" signal)
		(6 "In2.Cu" signal)
		(8 "In3.Cu" signal)
		(10 "In4.Cu" jumper)
		(12 "In5.Cu" signal)
		(14 "In6.Cu" signal)
		(16 "In7.Cu" signal)
		(18 "In8.Cu" signal)
		(2 "B.Cu" signal)
		(9 "F.Adhes" user "F.Adhesive")
		(11 "B.Adhes" user "B.Adhesive")
		(13 "F.Paste" user)
		(15 "B.Paste" user)
		(5 "F.SilkS" user "F.Silkscreen")
		(7 "B.SilkS" user "B.Silkscreen")
		(1 "F.Mask" user)
		(3 "B.Mask" user)
		(17 "Dwgs.User" user "User.Drawings")
		(19 "Cmts.User" user "User.Comments")
		(21 "Eco1.User" user "User.Eco1")
		(23 "Eco2.User" user "User.Eco2")
		(25 "Edge.Cuts" user)
		(27 "Margin" user)
		(31 "F.CrtYd" user "F.Courtyard")
		(29 "B.CrtYd" user "B.Courtyard")
		(35 "F.Fab" user)
		(33 "B.Fab" user)
	)
	(footprint "antmicro-footprints:Spacer_Drill3.7mm_H8mm_9774080151R"
		(locked yes)
		(layer "B.Cu")
		(at 216.930532 63.71 -90)
		(descr "Spacer M=3 h=8mm fi=5.1mm")
		(property "Reference" "H3"
			(at 0 3.2 90)
			(layer "B.SilkS")
			(effects
				(font
					(size 0.7 0.7)
					(thickness 0.15)
				)
				(justify left bottom mirror)
			)
		)
		(property "Value" "Spacer_Drill3.7mm_H8mm_9774080151R"
			(at 0 -4 90)
			(layer "B.Fab")
			(effects
				(font
					(size 0.7 0.7)
					(thickness 0.15)
				)
				(justify left bottom mirror)
			)
		)
		(property "Datasheet" "https://www.we-online.com/components/products/datasheet/9774080151R.pdf"
			(at 0 0 90)
			(layer "B.Fab")
			(hide yes)
			(effects
				(font
					(size 1.27 1.27)
					(thickness 0.15)
				)
				(justify mirror)
			)
		)
		(property "Description" "Spacer, SMT, Non Stop, Steel, Swage Round, 5.1 mm x 8 mm, M2.5 Thread, WA-SMSI Series"
			(at 0 0 90)
			(layer "B.Fab")
			(hide yes)
			(effects
				(font
					(size 1.27 1.27)
					(thickness 0.15)
				)
				(justify mirror)
			)
		)
		(property "Manufacturer" "Würth Elektronik"
			(at 0 0 270)
			(unlocked yes)
			(layer "B.Fab")
			(hide yes)
			(effects
				(font
					(size 1 1)
					(thickness 0.15)
				)
				(justify mirror)
			)
		)
		(property "MPN" "9774080151R"
			(at 0 0 270)
			(unlocked yes)
			(layer "B.Fab")
			(hide yes)
			(effects
				(font
					(size 1 1)
					(thickness 0.15)
				)
				(justify mirror)
			)
		)
		(property "Author" "Antmicro"
			(at 0 0 270)
			(unlocked yes)
			(layer "B.Fab")
			(hide yes)
			(effects
				(font
					(size 1 1)
					(thickness 0.15)
				)
				(justify mirror)
			)
		)
		(property "License" "Apache-2.0"
			(at 0 0 270)
			(unlocked yes)
			(layer "B.Fab")
			(hide yes)
			(effects
				(font
					(size 1 1)
					(thickness 0.15)
				)
				(justify mirror)
			)
		)
		(sheetname "/")
		(sheetfile "jetson-agx-thor-baseboard.kicad_sch")
		(solder_paste_margin_ratio -1)
		(attr smd)
		(fp_circle
			(center 0 0)
			(end 3.05 0)
			(stroke
				(width 0.05)
				(type solid)
			)
			(fill no)
			(layer "B.CrtYd")
		)
		(fp_circle
			(center 0 0)
			(end 2.6 0)
			(stroke
				(width 0.15)
				(type solid)
			)
			(fill no)
			(layer "B.Fab")
		)
		(fp_text user "Author: Antmicro"
			(at -9.6 -7.7 90)
			(layer "B.Fab")
			(effects
				(font
					(size 0.7 0.7)
					(thickness 0.15)
				)
				(justify left bottom mirror)
			)
		)
		(fp_text user "License: Apache-2.0"
			(at -9.6 -8.9 90)
			(layer "B.Fab")
			(effects
				(font
					(size 0.7 0.7)
					(thickness 0.15)
				)
				(justify left bottom mirror)
			)
		)
		(fp_text user "${REFERENCE}"
			(at -9.6 -6.5 90)
			(layer "B.Fab")
			(effects
				(font
					(size 0.7 0.7)
					(thickness 0.15)
				)
				(justify left bottom mirror)
			)
		)
		(pad "" smd custom
			(at -1.7 -1.7 180)
			(size 0.62 0.62)
			(layers "B.Paste")
			(thermal_bridge_angle 90)
			(options
				(clearance outline)
				(anchor circle)
			)
			(primitives
				(gr_arc
					(start 1.266786 0.24747)
					(mid 0.285453 -0.29439)
					(end -0.250195 -1.279127)
					(width 0.2)
				)
				(gr_arc
					(start 1.259603 0.339191)
					(mid 0.218448 -0.232561)
					(end -0.34334 -1.279127)
					(width 0.2)
				)
				(gr_arc
					(start 1.255279 0.431435)
					(mid 0.152481 -0.169693)
					(end -0.436309 -1.279127)
					(width 0.2)
				)
				(gr_arc
					(start 1.253811 0.524161)
					(mid 0.087542 -0.105784)
					(end -0.529126 -1.279127)
					(width 0.2)
				)
				(gr_arc
					(start 1.275473 0.621136)
					(mid 0.0309 -0.033527)
					(end -0.621807 -1.279127)
					(width 0.2)
				)
				(gr_arc
					(start 1.263664 0.711602)
					(mid -0.037759 0.026651)
					(end -0.71437 -1.279127)
					(width 0.2)
				)
				(gr_arc
					(start 1.253435 0.802342)
					(mid -0.105837 0.087395)
					(end -0.806826 -1.279127)
					(width 0.2)
				)
				(gr_arc
					(start 1.267475 0.897258)
					(mid -0.165236 0.156885)
					(end -0.899187 -1.279127)
					(width 0.2)
				)
				(gr_arc
					(start 1.270645 0.990112)
					(mid -0.228522 0.222449)
					(end -0.991463 -1.279127)
					(width 0.2)
				)
				(gr_arc
					(start 1.266278 1.081674)
					(mid -0.294507 0.285313)
					(end -1.083663 -1.279127)
					(width 0.2)
				)
				(gr_line
					(start 1.279127 0.250195)
					(end 1.279127 1.083663)
					(width 0.2)
				)
				(gr_line
					(start -0.250195 -1.279127)
					(end -1.083663 -1.279127)
					(width 0.2)
				)
			)
		)
		(pad "" smd custom
			(at -1.7 1.7 270)
			(size 0.62 0.62)
			(layers "B.Paste")
			(thermal_bridge_angle 90)
			(options
				(clearance outline)
				(anchor circle)
			)
			(primitives
				(gr_arc
					(start 1.266786 0.24747)
					(mid 0.285453 -0.29439)
					(end -0.250195 -1.279127)
					(width 0.2)
				)
				(gr_arc
					(start 1.259603 0.339191)
					(mid 0.218448 -0.232561)
					(end -0.34334 -1.279127)
					(width 0.2)
				)
				(gr_arc
					(start 1.255279 0.431435)
					(mid 0.152481 -0.169693)
					(end -0.436309 -1.279127)
					(width 0.2)
				)
				(gr_arc
					(start 1.253811 0.524161)
					(mid 0.087542 -0.105784)
					(end -0.529126 -1.279127)
					(width 0.2)
				)
				(gr_arc
					(start 1.275473 0.621136)
					(mid 0.0309 -0.033527)
					(end -0.621807 -1.279127)
					(width 0.2)
				)
				(gr_arc
					(start 1.263664 0.711602)
					(mid -0.037759 0.026651)
					(end -0.71437 -1.279127)
					(width 0.2)
				)
				(gr_arc
					(start 1.253435 0.802342)
					(mid -0.105837 0.087395)
					(end -0.806826 -1.279127)
					(width 0.2)
				)
				(gr_arc
					(start 1.267475 0.897258)
					(mid -0.165236 0.156885)
					(end -0.899187 -1.279127)
					(width 0.2)
				)
				(gr_arc
					(start 1.270645 0.990112)
					(mid -0.228522 0.222449)
					(end -0.991463 -1.279127)
					(width 0.2)
				)
				(gr_arc
					(start 1.266278 1.081674)
					(mid -0.294507 0.285313)
					(end -1.083663 -1.279127)
					(width 0.2)
				)
				(gr_line
					(start 1.279127 0.250195)
					(end 1.279127 1.083663)
					(width 0.2)
				)
				(gr_line
					(start -0.250195 -1.279127)
					(end -1.083663 -1.279127)
					(width 0.2)
				)
			)
		)
		(pad "" smd custom
			(at 1.7 -1.7 90)
			(size 0.62 0.62)
			(layers "B.Paste")
			(thermal_bridge_angle 90)
			(options
				(clearance outline)
				(anchor circle)
			)
			(primitives
				(gr_arc
					(start 1.266786 0.24747)
					(mid 0.285453 -0.29439)
					(end -0.250195 -1.279127)
					(width 0.2)
				)
				(gr_arc
					(start 1.259603 0.339191)
					(mid 0.218448 -0.232561)
					(end -0.34334 -1.279127)
					(width 0.2)
				)
				(gr_arc
					(start 1.255279 0.431435)
					(mid 0.152481 -0.169693)
					(end -0.436309 -1.279127)
					(width 0.2)
				)
				(gr_arc
					(start 1.253811 0.524161)
					(mid 0.087542 -0.105784)
					(end -0.529126 -1.279127)
					(width 0.2)
				)
				(gr_arc
					(start 1.275473 0.621136)
					(mid 0.0309 -0.033527)
					(end -0.621807 -1.279127)
					(width 0.2)
				)
				(gr_arc
					(start 1.263664 0.711602)
					(mid -0.037759 0.026651)
					(end -0.71437 -1.279127)
					(width 0.2)
				)
				(gr_arc
					(start 1.253435 0.802342)
					(mid -0.105837 0.087395)
					(end -0.806826 -1.279127)
					(width 0.2)
				)
				(gr_arc
					(start 1.267475 0.897258)
					(mid -0.165236 0.156885)
					(end -0.899187 -1.279127)
					(width 0.2)
				)
				(gr_arc
					(start 1.270645 0.990112)
					(mid -0.228522 0.222449)
					(end -0.991463 -1.279127)
					(width 0.2)
				)
				(gr_arc
					(start 1.266278 1.081674)
					(mid -0.294507 0.285313)
					(end -1.083663 -1.279127)
					(width 0.2)
				)
				(gr_line
					(start 1.279127 0.250195)
					(end 1.279127 1.083663)
					(width 0.2)
				)
				(gr_line
					(start -0.250195 -1.279127)
					(end -1.083663 -1.279127)
					(width 0.2)
				)
			)
		)
		(pad "" smd custom
			(at 1.7 1.7)
			(size 0.62 0.62)
			(layers "B.Paste")
			(thermal_bridge_angle 90)
			(options
				(clearance outline)
				(anchor circle)
			)
			(primitives
				(gr_arc
					(start 1.266786 0.24747)
					(mid 0.285453 -0.29439)
					(end -0.250195 -1.279127)
					(width 0.2)
				)
				(gr_arc
					(start 1.259603 0.339191)
					(mid 0.218448 -0.232561)
					(end -0.34334 -1.279127)
					(width 0.2)
				)
				(gr_arc
					(start 1.255279 0.431435)
					(mid 0.152481 -0.169693)
					(end -0.436309 -1.279127)
					(width 0.2)
				)
				(gr_arc
					(start 1.253811 0.524161)
					(mid 0.087542 -0.105784)
					(end -0.529126 -1.279127)
					(width 0.2)
				)
				(gr_arc
					(start 1.275473 0.621136)
					(mid 0.0309 -0.033527)
					(end -0.621807 -1.279127)
					(width 0.2)
				)
				(gr_arc
					(start 1.263664 0.711602)
					(mid -0.037759 0.026651)
					(end -0.71437 -1.279127)
					(width 0.2)
				)
				(gr_arc
					(start 1.253435 0.802342)
					(mid -0.105837 0.087395)
					(end -0.806826 -1.279127)
					(width 0.2)
				)
				(gr_arc
					(start 1.267475 0.897258)
					(mid -0.165236 0.156885)
					(end -0.899187 -1.279127)
					(width 0.2)
				)
				(gr_arc
					(start 1.270645 0.990112)
					(mid -0.228522 0.222449)
					(end -0.991463 -1.279127)
					(width 0.2)
				)
				(gr_arc
					(start 1.266278 1.081674)
					(mid -0.294507 0.285313)
					(end -1.083663 -1.279127)
					(width 0.2)
				)
				(gr_line
					(start 1.279127 0.250195)
					(end 1.279127 1.083663)
					(width 0.2)
				)
				(gr_line
					(start -0.250195 -1.279127)
					(end -1.083663 -1.279127)
					(width 0.2)
				)
			)
		)
		(pad "1" thru_hole circle
			(at 0 0 270)
			(size 6 6)
			(drill 3.7)
			(layers "*.Cu" "*.Mask")
			(remove_unused_layers no)
			(net 1 "GND")
			(pintype "passive")
		)
	)
	(footprint "antmicro-footprints:R_0402_1005Metric"
		(layer "B.Cu")
		(at 203.4 103.8 180)
		(descr "Resistor SMD 0402")
		(tags "resistor SMD 0402")
		(property "Reference" "R278"
			(at -3.85 -0.5 0)
			(layer "B.SilkS")
			(effects
				(font
					(size 0.7 0.7)
					(thickness 0.15)
				)
				(justify left bottom mirror)
			)
		)
		(property "Value" "R_10k_0402"
			(at -1.011843 -1.772046 0)
			(layer "B.Fab")
			(effects
				(font
					(size 0.7 0.7)
					(thickness 0.15)
				)
				(justify left bottom mirror)
			)
		)
		(property "Datasheet" "https://www.bourns.com/docs/product-datasheets/cr.pdf"
			(at 0 0 0)
			(layer "B.Fab")
			(hide yes)
			(effects
				(font
					(size 1.27 1.27)
					(thickness 0.15)
				)
				(justify mirror)
			)
		)
		(property "Description" "SMD Chip Resistor, 10 kohm, ± 1%, 62.5 mW, 0402 [1005 Metric], Thick Film, General Purpose"
			(at 0 0 0)
			(layer "B.Fab")
			(hide yes)
			(effects
				(font
					(size 1.27 1.27)
					(thickness 0.15)
				)
				(justify mirror)
			)
		)
		(property "Manufacturer" "Bourns"
			(at 0 0 0)
			(unlocked yes)
			(layer "B.Fab")
			(hide yes)
			(effects
				(font
					(size 1 1)
					(thickness 0.15)
				)
				(justify mirror)
			)
		)
		(property "MPN" "CR0402-FX-1002GLF"
			(at 0 0 0)
			(unlocked yes)
			(layer "B.Fab")
			(hide yes)
			(effects
				(font
					(size 1 1)
					(thickness 0.15)
				)
				(justify mirror)
			)
		)
		(property "Val" "10k"
			(at 0 0 0)
			(unlocked yes)
			(layer "B.Fab")
			(hide yes)
			(effects
				(font
					(size 1 1)
					(thickness 0.15)
				)
				(justify mirror)
			)
		)
		(property "License" "Apache-2.0"
			(at 0 0 0)
			(unlocked yes)
			(layer "B.Fab")
			(hide yes)
			(effects
				(font
					(size 1 1)
					(thickness 0.15)
				)
				(justify mirror)
			)
		)
		(property "Author" "Antmicro"
			(at 0 0 0)
			(unlocked yes)
			(layer "B.Fab")
			(hide yes)
			(effects
				(font
					(size 1 1)
					(thickness 0.15)
				)
				(justify mirror)
			)
		)
		(property "Tolerance" "1%"
			(at 0 0 0)
			(unlocked yes)
			(layer "B.Fab")
			(hide yes)
			(effects
				(font
					(size 1 1)
					(thickness 0.15)
				)
				(justify mirror)
			)
		)
		(sheetname "/Recovery USB/")
		(sheetfile "recovery_usb.kicad_sch")
		(attr smd)
		(fp_poly
			(pts
				(xy -0.925 0.47) (xy 0.925 0.47) (xy 0.925 -0.47) (xy -0.925 -0.47)
			)
			(stroke
				(width 0.05)
				(type default)
			)
			(fill no)
			(layer "B.CrtYd")
		)
		(fp_poly
			(pts
				(xy -0.5 0.25) (xy 0.5 0.25) (xy 0.5 -0.25) (xy -0.5 -0.25)
			)
			(stroke
				(width 0.15)
				(type solid)
			)
			(fill no)
			(layer "B.Fab")
		)
		(fp_text user "Author: Antmicro"
			(at -0.95 -4.169 0)
			(layer "B.Fab")
			(effects
				(font
					(size 0.7 0.7)
					(thickness 0.15)
				)
				(justify left bottom mirror)
			)
		)
		(fp_text user "License: Apache-2.0"
			(at -0.949999 -5.169 0)
			(layer "B.Fab")
			(effects
				(font
					(size 0.7 0.7)
					(thickness 0.15)
				)
				(justify left bottom mirror)
			)
		)
		(fp_text user "${REFERENCE}"
			(at -0.95 -3.168 0)
			(layer "B.Fab")
			(effects
				(font
					(size 0.7 0.7)
					(thickness 0.15)
				)
				(justify left bottom mirror)
			)
		)
		(pad "1" smd roundrect
			(at -0.48 0 180)
			(size 0.59 0.64)
			(layers "B.Cu" "B.Mask" "B.Paste")
			(roundrect_rratio 0.25)
			(net 1023 "/Recovery USB/USBC2_I_MODE")
			(pintype "passive")
		)
		(pad "2" smd roundrect
			(at 0.48 0 180)
			(size 0.59 0.64)
			(layers "B.Cu" "B.Mask" "B.Paste")
			(roundrect_rratio 0.25)
			(net 5 "+5V")
			(pintype "passive")
		)
	)
	(footprint "antmicro-footprints:C_0402_1005Metric"
		(layer "B.Cu")
		(at 137.2 71.2 180)
		(descr "Capacitor SMD 0402")
		(tags "capacitor SMD 0402")
		(property "Reference" "C272"
			(at -1.42 0.68 0)
			(layer "B.SilkS")
			(effects
				(font
					(size 0.7 0.7)
					(thickness 0.15)
				)
				(justify left bottom mirror)
			)
		)
		(property "Value" "C_100n_0402"
			(at -1.022927 -2.155213 0)
			(layer "B.Fab")
			(effects
				(font
					(size 0.7 0.7)
					(thickness 0.15)
				)
				(justify left bottom mirror)
			)
		)
		(property "Datasheet" "https://www.murata.com/products/productdetail?partno=GRM155R61H104KE14%23"
			(at 0 0 0)
			(layer "B.Fab")
			(hide yes)
			(effects
				(font
					(size 1.27 1.27)
					(thickness 0.15)
				)
				(justify mirror)
			)
		)
		(property "Description" "SMD Multilayer Ceramic Capacitor, 0.1 µF, 50 V, 0402 [1005 Metric], ± 10%, X5R, GRM Series"
			(at 0 0 0)
			(layer "B.Fab")
			(hide yes)
			(effects
				(font
					(size 1.27 1.27)
					(thickness 0.15)
				)
				(justify mirror)
			)
		)
		(property "MPN" "GRM155R61H104KE14D"
			(at 0 0 0)
			(unlocked yes)
			(layer "B.Fab")
			(hide yes)
			(effects
				(font
					(size 1 1)
					(thickness 0.15)
				)
				(justify mirror)
			)
		)
		(property "Val" "100n"
			(at 0 0 0)
			(unlocked yes)
			(layer "B.Fab")
			(hide yes)
			(effects
				(font
					(size 1 1)
					(thickness 0.15)
				)
				(justify mirror)
			)
		)
		(property "Voltage" "50V"
			(at 0 0 0)
			(unlocked yes)
			(layer "B.Fab")
			(hide yes)
			(effects
				(font
					(size 1 1)
					(thickness 0.15)
				)
				(justify mirror)
			)
		)
		(property "Dielectric" "X5R"
			(at 0 0 0)
			(unlocked yes)
			(layer "B.Fab")
			(hide yes)
			(effects
				(font
					(size 1 1)
					(thickness 0.15)
				)
				(justify mirror)
			)
		)
		(property "Manufacturer" "Murata"
			(at 0 0 0)
			(unlocked yes)
			(layer "B.Fab")
			(hide yes)
			(effects
				(font
					(size 1 1)
					(thickness 0.15)
				)
				(justify mirror)
			)
		)
		(property "License" "Apache-2.0"
			(at 0 0 0)
			(unlocked yes)
			(layer "B.Fab")
			(hide yes)
			(effects
				(font
					(size 1 1)
					(thickness 0.15)
				)
				(justify mirror)
			)
		)
		(property "Author" "Antmicro"
			(at 0 0 0)
			(unlocked yes)
			(layer "B.Fab")
			(hide yes)
			(effects
				(font
					(size 1 1)
					(thickness 0.15)
				)
				(justify mirror)
			)
		)
		(sheetname "/SoM_Power/")
		(sheetfile "som_power.kicad_sch")
		(attr smd)
		(fp_poly
			(pts
				(xy -0.925 0.47) (xy -0.925 -0.47) (xy 0.925 -0.47) (xy 0.925 0.47)
			)
			(stroke
				(width 0.05)
				(type default)
			)
			(fill no)
			(layer "B.CrtYd")
		)
		(fp_line
			(start 0.504 0.25)
			(end 0.504 -0.248)
			(stroke
				(width 0.15)
				(type solid)
			)
			(layer "B.Fab")
		)
		(fp_line
			(start 0.504 -0.248)
			(end -0.494 -0.248)
			(stroke
				(width 0.15)
				(type solid)
			)
			(layer "B.Fab")
		)
		(fp_line
			(start -0.494 0.25)
			(end 0.504 0.25)
			(stroke
				(width 0.15)
				(type solid)
			)
			(layer "B.Fab")
		)
		(fp_line
			(start -0.494 -0.248)
			(end -0.494 0.25)
			(stroke
				(width 0.15)
				(type solid)
			)
			(layer "B.Fab")
		)
		(fp_text user "${REFERENCE}"
			(at -0.939 -4.599 0)
			(layer "B.Fab")
			(effects
				(font
					(size 0.7 0.7)
					(thickness 0.15)
				)
				(justify left bottom mirror)
			)
		)
		(fp_text user "Author: Antmicro"
			(at -0.939 -3.399 0)
			(layer "B.Fab")
			(effects
				(font
					(size 0.7 0.7)
					(thickness 0.15)
				)
				(justify left bottom mirror)
			)
		)
		(fp_text user "License: Apache-2.0"
			(at -0.939 -5.799 0)
			(layer "B.Fab")
			(effects
				(font
					(size 0.7 0.7)
					(thickness 0.15)
				)
				(justify left bottom mirror)
			)
		)
		(pad "1" smd roundrect
			(at -0.48 0 180)
			(size 0.59 0.64)
			(layers "B.Cu" "B.Mask" "B.Paste")
			(roundrect_rratio 0.25)
			(net 1 "GND")
			(pintype "passive")
		)
		(pad "2" smd roundrect
			(at 0.48 0 180)
			(size 0.59 0.64)
			(layers "B.Cu" "B.Mask" "B.Paste")
			(roundrect_rratio 0.25)
			(net 4 "+3V3_AON")
			(pintype "passive")
		)
	)
	(footprint "antmicro-footprints:TP_SMD_0.75mm"
		(layer "B.Cu")
		(at 91.4 83.4 -90)
		(property "Reference" "TP101"
			(at -2.595 -1.63 90)
			(layer "B.SilkS")
			(effects
				(font
					(size 0.7 0.7)
					(thickness 0.15)
				)
				(justify left bottom mirror)
			)
		)
		(property "Value" "TP_0.75mm_SMD"
			(at 0 -1.2 90)
			(layer "B.Fab")
			(effects
				(font
					(size 0.7 0.7)
					(thickness 0.15)
				)
				(justify left bottom mirror)
			)
		)
		(property "Description" "SMT test point"
			(at 0 0 90)
			(layer "B.Fab")
			(hide yes)
			(effects
				(font
					(size 1.27 1.27)
					(thickness 0.15)
				)
				(justify mirror)
			)
		)
		(property "MPN" ""
			(at 0 0 90)
			(unlocked yes)
			(layer "B.Fab")
			(hide yes)
			(effects
				(font
					(size 1 1)
					(thickness 0.15)
				)
				(justify mirror)
			)
		)
		(property "Manufacturer" ""
			(at 0 0 90)
			(unlocked yes)
			(layer "B.Fab")
			(hide yes)
			(effects
				(font
					(size 1 1)
					(thickness 0.15)
				)
				(justify mirror)
			)
		)
		(property "Author" "Antmicro"
			(at 0 0 90)
			(unlocked yes)
			(layer "B.Fab")
			(hide yes)
			(effects
				(font
					(size 1 1)
					(thickness 0.15)
				)
				(justify mirror)
			)
		)
		(property "License" "Apache-2.0"
			(at 0 0 90)
			(unlocked yes)
			(layer "B.Fab")
			(hide yes)
			(effects
				(font
					(size 1 1)
					(thickness 0.15)
				)
				(justify mirror)
			)
		)
		(sheetname "/SoM_IO/")
		(sheetfile "som_io.kicad_sch")
		(attr exclude_from_pos_files exclude_from_bom)
		(fp_circle
			(center 0 0)
			(end 0.475 0)
			(stroke
				(width 0.05)
				(type default)
			)
			(fill no)
			(layer "B.CrtYd")
		)
		(fp_text user "${REFERENCE}"
			(at -0.4 -2.7 90)
			(layer "B.Fab")
			(effects
				(font
					(size 0.7 0.7)
					(thickness 0.15)
				)
				(justify left bottom mirror)
			)
		)
		(fp_text user "License: Apache-2.0"
			(at -0.4 -5.101 90)
			(layer "B.Fab")
			(effects
				(font
					(size 0.7 0.7)
					(thickness 0.15)
				)
				(justify left bottom mirror)
			)
		)
		(fp_text user "Author: Antmicro"
			(at -0.4 -3.901 90)
			(layer "B.Fab")
			(effects
				(font
					(size 0.7 0.7)
					(thickness 0.15)
				)
				(justify left bottom mirror)
			)
		)
		(pad "1" smd circle
			(at 0 0 270)
			(size 0.75 0.75)
			(layers "B.Cu" "B.Mask")
			(net 72 "/SoM_IO/I2S_{M.2}.SDOUT")
			(pinfunction "1")
			(pintype "passive")
		)
	)
)
